(kicad_pcb
	(version 20260206)
	(generator "pcbnew")
	(generator_version "10.0")
	(general
		(thickness 1.6)
		(legacy_teardrops no)
	)
	(paper "A4")
	(title_block
		(title "03242023_DA0F0TMBIJ0_F0T_Motherboard_J_brd_V01_OCP.brd")
		(comment 1 "Grand Teton / footprints 5163-5168 of 6105")
	)
	(layers
		(0 "F.Cu" signal "TOP")
		(4 "In1.Cu" signal "GND")
		(6 "In2.Cu" signal "IN1")
		(8 "In3.Cu" signal "GND1")
		(10 "In4.Cu" signal "IN2")
		(12 "In5.Cu" signal "GND2")
		(14 "In6.Cu" signal "IN3")
		(16 "In7.Cu" signal "GND3")
		(18 "In8.Cu" signal "VCC")
		(20 "In9.Cu" signal "VCC1")
		(22 "In10.Cu" signal "GND4")
		(24 "In11.Cu" signal "IN4")
		(26 "In12.Cu" signal "GND5")
		(28 "In13.Cu" signal "IN5")
		(30 "In14.Cu" signal "GND6")
		(32 "In15.Cu" signal "IN6")
		(34 "In16.Cu" signal "GND7")
		(2 "B.Cu" signal "BOTTOM")
		(9 "F.Adhes" user "F.Adhesive")
		(11 "B.Adhes" user "B.Adhesive")
		(13 "F.Paste" user "Package Geometry/Pastemask Top")
		(15 "B.Paste" user "Package Geometry/Pastemask Bottom")
		(5 "F.SilkS" user "Ref Des/Silkscreen Top")
		(7 "B.SilkS" user "Ref Des/Silkscreen Bottom")
		(1 "F.Mask" user "Board Geometry/Soldermask Top")
		(3 "B.Mask" user "Board Geometry/Soldermask Bottom")
		(17 "Dwgs.User" user "User.Drawings")
		(19 "Cmts.User" user "User.Comments")
		(21 "Eco1.User" user "User.Eco1")
		(23 "Eco2.User" user "User.Eco2")
		(25 "Edge.Cuts" user "Board Geometry/Outline")
		(27 "Margin" user)
		(31 "F.CrtYd" user "Package Geometry/Place Bound Top")
		(29 "B.CrtYd" user "Package Geometry/Place Bound Bottom")
		(35 "F.Fab" user "Ref Des/Assembly Top")
		(33 "B.Fab" user "Ref Des/Assembly Bottom")
	)
	(footprint ""
		(layer "B.Cu")
		(at 490.57433 -303.547272 -90)
		(property "Reference" "X12"
			(at 3.322828 3.706876 270)
			(unlocked yes)
			(layer "B.SilkS")
			(effects
				(font
					(size 0.7874 0.5842)
					(thickness 0.1524)
				)
				(justify left mirror)
			)
		)
		(property "Value" ""
			(at 0 0 90)
			(layer "B.Fab")
			(effects
				(font
					(size 1.27 1.27)
				)
				(justify mirror)
			)
		)
		(property "Device Type" "TP_TDR_4P_FTS_MPKT4_H025P0200_I"
			(at -1.30175 1.27 180)
			(unlocked yes)
			(layer "B.Fab")
			(hide yes)
			(effects
				(font
					(size 0.635 0.4064)
					(thickness 0.1524)
				)
				(justify mirror)
			)
		)
		(property "User Part Number" "TP15"
			(at -1.30175 1.27 180)
			(unlocked yes)
			(layer "Cmts.User")
			(hide yes)
			(effects
				(font
					(size 0.635 0.4064)
					(thickness 0.1524)
				)
				(justify mirror)
			)
		)
		(duplicate_pad_numbers_are_jumpers no)
		(fp_line
			(start -2.54 3.81)
			(end -2.54 3.6703)
			(stroke
				(width 0.1524)
				(type default)
			)
			(layer "B.SilkS")
		)
		(fp_line
			(start 0 3.81)
			(end -2.54 3.81)
			(stroke
				(width 0.1524)
				(type default)
			)
			(layer "B.SilkS")
		)
		(fp_line
			(start 0 3.175)
			(end 0 3.81)
			(stroke
				(width 0.1524)
				(type default)
			)
			(layer "B.SilkS")
		)
		(fp_line
			(start -2.54 1.4097)
			(end -2.54 1.1303)
			(stroke
				(width 0.1524)
				(type default)
			)
			(layer "B.SilkS")
		)
		(fp_line
			(start 0 0.635)
			(end 0 1.905)
			(stroke
				(width 0.1524)
				(type default)
			)
			(layer "B.SilkS")
		)
		(fp_line
			(start -2.54 -1.1303)
			(end -2.54 -1.27)
			(stroke
				(width 0.1524)
				(type default)
			)
			(layer "B.SilkS")
		)
		(fp_line
			(start -2.54 -1.27)
			(end 0 -1.27)
			(stroke
				(width 0.1524)
				(type default)
			)
			(layer "B.SilkS")
		)
		(fp_line
			(start 0 -1.27)
			(end 0 -0.635)
			(stroke
				(width 0.1524)
				(type default)
			)
			(layer "B.SilkS")
		)
		(fp_poly
			(pts
				(xy 2.853944 -0.825246) (xy 2.853944 0.698754) (xy 1.329944 -0.063246)
			)
			(stroke
				(width 0)
				(type default)
			)
			(fill yes)
			(layer "B.SilkS")
		)
		(fp_line
			(start -2.54 3.81)
			(end -2.54 -1.27)
			(stroke
				(width 0.1)
				(type default)
			)
			(layer "B.Fab")
		)
		(fp_line
			(start 0 3.81)
			(end -2.54 3.81)
			(stroke
				(width 0.1)
				(type default)
			)
			(layer "B.Fab")
		)
		(fp_line
			(start -2.54 -1.27)
			(end 0 -1.27)
			(stroke
				(width 0.1)
				(type default)
			)
			(layer "B.Fab")
		)
		(fp_line
			(start 0 -1.27)
			(end 0 3.81)
			(stroke
				(width 0.1)
				(type default)
			)
			(layer "B.Fab")
		)
		(fp_poly
			(pts
				(xy 0.761746 0) (xy 2.285746 -0.762) (xy 2.285746 0.762)
			)
			(stroke
				(width 0)
				(type default)
			)
			(fill yes)
			(layer "B.Fab")
		)
		(pad "1" thru_hole circle
			(at 0 0 90)
			(size 1.0033 1.0033)
			(drill 0.249936)
			(layers "*.Cu" "*.Mask")
			(remove_unused_layers no)
			(net "TDR_DIFF_85_BOT_DN")
			(clearance 0.10795)
			(padstack
				(mode front_inner_back)
				(layer "Inner"
					(shape circle)
					(size 0.8001 0.8001)
					(clearance 0.1524)
				)
				(layer "B.Cu"
					(shape circle)
					(size 1.0033 1.0033)
					(thermal_gap 0.10795)
					(clearance 0.10795)
				)
			)
		)
		(pad "2" thru_hole circle
			(at -2.54 0 90)
			(size 1.9939 1.9939)
			(drill 0.249936)
			(layers "*.Cu" "*.Mask")
			(remove_unused_layers no)
			(net "T1_GND")
			(clearance 0.10795)
			(padstack
				(mode front_inner_back)
				(layer "Inner"
					(shape circle)
					(size 0.8001 0.8001)
					(clearance 0.1524)
				)
				(layer "B.Cu"
					(shape circle)
					(size 1.9939 1.9939)
					(thermal_gap 0.10795)
					(clearance 0.10795)
				)
			)
		)
		(pad "3" thru_hole circle
			(at -2.54 2.54 90)
			(size 1.9939 1.9939)
			(drill 0.249936)
			(layers "*.Cu" "*.Mask")
			(remove_unused_layers no)
			(net "T1_GND")
			(clearance 0.10795)
			(padstack
				(mode front_inner_back)
				(layer "Inner"
					(shape circle)
					(size 0.8001 0.8001)
					(clearance 0.1524)
				)
				(layer "B.Cu"
					(shape circle)
					(size 1.9939 1.9939)
					(thermal_gap 0.10795)
					(clearance 0.10795)
				)
			)
		)
		(pad "4" thru_hole circle
			(at 0 2.54 90)
			(size 1.0033 1.0033)
			(drill 0.249936)
			(layers "*.Cu" "*.Mask")
			(remove_unused_layers no)
			(net "TDR_DIFF_85_BOT_DP")
			(clearance 0.10795)
			(padstack
				(mode front_inner_back)
				(layer "Inner"
					(shape circle)
					(size 0.8001 0.8001)
					(clearance 0.1524)
				)
				(layer "B.Cu"
					(shape circle)
					(size 1.0033 1.0033)
					(thermal_gap 0.10795)
					(clearance 0.10795)
				)
			)
		)
	)
	(footprint ""
		(layer "B.Cu")
		(at 98.511868 -404.486618 -90)
		(property "Reference" "C2074"
			(at 0 0 90)
			(layer "B.SilkS")
			(hide yes)
			(effects
				(font
					(size 1.27 1.27)
				)
				(justify mirror)
			)
		)
		(property "Value" ""
			(at 0 0 90)
			(layer "B.Fab")
			(effects
				(font
					(size 1.27 1.27)
				)
				(justify mirror)
			)
		)
		(duplicate_pad_numbers_are_jumpers no)
		(fp_line
			(start -0.299974 0.150114)
			(end 0.299974 0.150114)
			(stroke
				(width 0.1)
				(type default)
			)
			(layer "B.Fab")
		)
		(fp_line
			(start 0.299974 0.150114)
			(end 0.299974 -0.150114)
			(stroke
				(width 0.1)
				(type default)
			)
			(layer "B.Fab")
		)
		(fp_line
			(start -0.299974 -0.150114)
			(end -0.299974 0.150114)
			(stroke
				(width 0.1)
				(type default)
			)
			(layer "B.Fab")
		)
		(fp_line
			(start 0.299974 -0.150114)
			(end -0.299974 -0.150114)
			(stroke
				(width 0.1)
				(type default)
			)
			(layer "B.Fab")
		)
		(pad "1" smd rect
			(at 0.2667 0 90)
			(size 0.3048 0.381)
			(layers "B.Cu" "B.Mask" "B.Paste")
			(net "P3E_PCH_NVS_TX_DN<1>")
		)
		(pad "2" smd rect
			(at -0.2667 0 90)
			(size 0.3048 0.381)
			(layers "B.Cu" "B.Mask" "B.Paste")
			(net "P3E_PCH_NVS_TX_C_DN<1>")
		)
		(zone
			(layer "In16.Cu")
			(hatch none 0.5)
			(connect_pads
				(clearance 0)
			)
			(min_thickness 0.25)
			(keepout
				(tracks not_allowed)
				(vias allowed)
				(pads allowed)
				(copperpour not_allowed)
				(footprints allowed)
			)
			(placement
				(enabled no)
				(sheetname "")
			)
			(fill
				(thermal_gap 0.5)
				(thermal_bridge_width 0.5)
				(island_removal_mode 0)
			)
			(polygon
				(pts
					(arc
						(start 98.270568 -404.626318)
						(mid 98.292886 -404.572436)
						(end 98.346768 -404.550118)
					)
					(arc
						(start 98.676968 -404.550118)
						(mid 98.73085 -404.572436)
						(end 98.753168 -404.626318)
					)
					(arc
						(start 98.753168 -404.880318)
						(mid 98.73085 -404.9342)
						(end 98.676968 -404.956518)
					)
					(arc
						(start 98.346768 -404.956518)
						(mid 98.292886 -404.9342)
						(end 98.270568 -404.880318)
					)
				)
			)
		)
		(zone
			(layer "In16.Cu")
			(hatch none 0.5)
			(connect_pads
				(clearance 0)
			)
			(min_thickness 0.25)
			(keepout
				(tracks not_allowed)
				(vias allowed)
				(pads allowed)
				(copperpour not_allowed)
				(footprints allowed)
			)
			(placement
				(enabled no)
				(sheetname "")
			)
			(fill
				(thermal_gap 0.5)
				(thermal_bridge_width 0.5)
				(island_removal_mode 0)
			)
			(polygon
				(pts
					(arc
						(start 98.270568 -404.092918)
						(mid 98.292886 -404.039036)
						(end 98.346768 -404.016718)
					)
					(arc
						(start 98.676968 -404.016718)
						(mid 98.73085 -404.039036)
						(end 98.753168 -404.092918)
					)
					(arc
						(start 98.753168 -404.346918)
						(mid 98.73085 -404.4008)
						(end 98.676968 -404.423118)
					)
					(arc
						(start 98.346768 -404.423118)
						(mid 98.292886 -404.4008)
						(end 98.270568 -404.346918)
					)
				)
			)
		)
	)
	(footprint ""
		(layer "B.Cu")
		(at 366.120934 -248.498106 -90)
		(property "Reference" "C376"
			(at 0 0 90)
			(layer "B.SilkS")
			(hide yes)
			(effects
				(font
					(size 1.27 1.27)
				)
				(justify mirror)
			)
		)
		(property "Value" ""
			(at 0 0 90)
			(layer "B.Fab")
			(effects
				(font
					(size 1.27 1.27)
				)
				(justify mirror)
			)
		)
		(duplicate_pad_numbers_are_jumpers no)
		(fp_line
			(start -1.524 0.762)
			(end 1.524 0.762)
			(stroke
				(width 0.1524)
				(type default)
			)
			(layer "B.SilkS")
		)
		(fp_line
			(start 1.524 0.762)
			(end 1.524 -0.762)
			(stroke
				(width 0.1524)
				(type default)
			)
			(layer "B.SilkS")
		)
		(fp_line
			(start -1.524 -0.762)
			(end -1.524 0.762)
			(stroke
				(width 0.1524)
				(type default)
			)
			(layer "B.SilkS")
		)
		(fp_line
			(start 1.524 -0.762)
			(end -1.524 -0.762)
			(stroke
				(width 0.1524)
				(type default)
			)
			(layer "B.SilkS")
		)
		(fp_line
			(start -1.1049 0.724916)
			(end -1.1049 -0.724916)
			(stroke
				(width 0.1)
				(type default)
			)
			(layer "B.Fab")
		)
		(fp_line
			(start 1.1049 0.724916)
			(end -1.1049 0.724916)
			(stroke
				(width 0.1)
				(type default)
			)
			(layer "B.Fab")
		)
		(fp_line
			(start -1.1049 -0.724916)
			(end 1.1049 -0.724916)
			(stroke
				(width 0.1)
				(type default)
			)
			(layer "B.Fab")
		)
		(fp_line
			(start 1.1049 -0.724916)
			(end 1.1049 0.724916)
			(stroke
				(width 0.1)
				(type default)
			)
			(layer "B.Fab")
		)
		(pad "1" smd rect
			(at 0.889 0 270)
			(size 1.016 1.27)
			(layers "B.Cu" "B.Mask" "B.Paste")
			(net "PVCCIN_CPU0")
		)
		(pad "2" smd rect
			(at -0.889 0 270)
			(size 1.016 1.27)
			(layers "B.Cu" "B.Mask" "B.Paste")
			(net "GND")
		)
	)
	(footprint ""
		(layer "B.Cu")
		(at 427.466252 -124.025152)
		(property "Reference" "PR409"
			(at 0 0 0)
			(layer "B.SilkS")
			(hide yes)
			(effects
				(font
					(size 1.27 1.27)
				)
				(justify mirror)
			)
		)
		(property "Value" ""
			(at 0 0 0)
			(layer "B.Fab")
			(effects
				(font
					(size 1.27 1.27)
				)
				(justify mirror)
			)
		)
		(duplicate_pad_numbers_are_jumpers no)
		(fp_line
			(start -0.7874 -0.4064)
			(end -0.7874 0.4064)
			(stroke
				(width 0.1524)
				(type default)
			)
			(layer "B.SilkS")
		)
		(fp_line
			(start -0.7874 0.4064)
			(end 0.7874 0.4064)
			(stroke
				(width 0.1524)
				(type default)
			)
			(layer "B.SilkS")
		)
		(fp_line
			(start 0.7874 -0.4064)
			(end -0.7874 -0.4064)
			(stroke
				(width 0.1524)
				(type default)
			)
			(layer "B.SilkS")
		)
		(fp_line
			(start 0.7874 0.4064)
			(end 0.7874 -0.4064)
			(stroke
				(width 0.1524)
				(type default)
			)
			(layer "B.SilkS")
		)
		(fp_line
			(start -0.67945 -0.3048)
			(end -0.67945 0.3048)
			(stroke
				(width 0.1)
				(type default)
			)
			(layer "B.Fab")
		)
		(fp_line
			(start -0.67945 0.3048)
			(end -0.120396 0.3048)
			(stroke
				(width 0.1)
				(type default)
			)
			(layer "B.Fab")
		)
		(fp_line
			(start -0.12065 -0.3048)
			(end -0.67945 -0.3048)
			(stroke
				(width 0.1)
				(type default)
			)
			(layer "B.Fab")
		)
		(fp_line
			(start -0.12065 -0.2794)
			(end -0.12065 -0.3048)
			(stroke
				(width 0.1)
				(type default)
			)
			(layer "B.Fab")
		)
		(fp_line
			(start -0.120396 0.2794)
			(end 0.12065 0.2794)
			(stroke
				(width 0.1)
				(type default)
			)
			(layer "B.Fab")
		)
		(fp_line
			(start -0.120396 0.3048)
			(end -0.120396 0.2794)
			(stroke
				(width 0.1)
				(type default)
			)
			(layer "B.Fab")
		)
		(fp_line
			(start 0.12065 -0.305054)
			(end 0.12065 -0.2794)
			(stroke
				(width 0.1)
				(type default)
			)
			(layer "B.Fab")
		)
		(fp_line
			(start 0.12065 -0.2794)
			(end -0.12065 -0.2794)
			(stroke
				(width 0.1)
				(type default)
			)
			(layer "B.Fab")
		)
		(fp_line
			(start 0.12065 0.2794)
			(end 0.12065 0.3048)
			(stroke
				(width 0.1)
				(type default)
			)
			(layer "B.Fab")
		)
		(fp_line
			(start 0.12065 0.3048)
			(end 0.67945 0.3048)
			(stroke
				(width 0.1)
				(type default)
			)
			(layer "B.Fab")
		)
		(fp_line
			(start 0.67945 -0.305054)
			(end 0.12065 -0.305054)
			(stroke
				(width 0.1)
				(type default)
			)
			(layer "B.Fab")
		)
		(fp_line
			(start 0.67945 0.3048)
			(end 0.67945 -0.305054)
			(stroke
				(width 0.1)
				(type default)
			)
			(layer "B.Fab")
		)
		(pad "1" smd circle
			(at 0.40005 0 180)
			(size 0 0)
			(layers "B.Cu" "B.Mask" "B.Paste")
			(net "PVCCD_HV_CPU0_ISYS_R")
		)
		(pad "2" smd circle
			(at -0.40005 0 180)
			(size 0 0)
			(layers "B.Cu" "B.Mask" "B.Paste")
			(net "PVCCD_HV_CPU0_NVDIMM_ISENSE")
		)
	)
	(footprint ""
		(layer "B.Cu")
		(at 284.446726 -193.691256 -90)
		(property "Reference" "R706"
			(at 0 0 90)
			(layer "B.SilkS")
			(hide yes)
			(effects
				(font
					(size 1.27 1.27)
				)
				(justify mirror)
			)
		)
		(property "Value" ""
			(at 0 0 90)
			(layer "B.Fab")
			(effects
				(font
					(size 1.27 1.27)
				)
				(justify mirror)
			)
		)
		(duplicate_pad_numbers_are_jumpers no)
		(fp_line
			(start -0.7874 0.4064)
			(end 0.7874 0.4064)
			(stroke
				(width 0.1524)
				(type default)
			)
			(layer "B.SilkS")
		)
		(fp_line
			(start 0.7874 0.4064)
			(end 0.7874 -0.4064)
			(stroke
				(width 0.1524)
				(type default)
			)
			(layer "B.SilkS")
		)
		(fp_line
			(start -0.7874 -0.4064)
			(end -0.7874 0.4064)
			(stroke
				(width 0.1524)
				(type default)
			)
			(layer "B.SilkS")
		)
		(fp_line
			(start 0.7874 -0.4064)
			(end -0.7874 -0.4064)
			(stroke
				(width 0.1524)
				(type default)
			)
			(layer "B.SilkS")
		)
		(fp_line
			(start -0.67945 0.3048)
			(end -0.120396 0.3048)
			(stroke
				(width 0.1)
				(type default)
			)
			(layer "B.Fab")
		)
		(fp_line
			(start -0.120396 0.3048)
			(end -0.120396 0.2794)
			(stroke
				(width 0.1)
				(type default)
			)
			(layer "B.Fab")
		)
		(fp_line
			(start 0.12065 0.3048)
			(end 0.67945 0.3048)
			(stroke
				(width 0.1)
				(type default)
			)
			(layer "B.Fab")
		)
		(fp_line
			(start 0.67945 0.3048)
			(end 0.67945 -0.305054)
			(stroke
				(width 0.1)
				(type default)
			)
			(layer "B.Fab")
		)
		(fp_line
			(start -0.120396 0.2794)
			(end 0.12065 0.2794)
			(stroke
				(width 0.1)
				(type default)
			)
			(layer "B.Fab")
		)
		(fp_line
			(start 0.12065 0.2794)
			(end 0.12065 0.3048)
			(stroke
				(width 0.1)
				(type default)
			)
			(layer "B.Fab")
		)
		(fp_line
			(start -0.12065 -0.2794)
			(end -0.12065 -0.3048)
			(stroke
				(width 0.1)
				(type default)
			)
			(layer "B.Fab")
		)
		(fp_line
			(start 0.12065 -0.2794)
			(end -0.12065 -0.2794)
			(stroke
				(width 0.1)
				(type default)
			)
			(layer "B.Fab")
		)
		(fp_line
			(start -0.67945 -0.3048)
			(end -0.67945 0.3048)
			(stroke
				(width 0.1)
				(type default)
			)
			(layer "B.Fab")
		)
		(fp_line
			(start -0.12065 -0.3048)
			(end -0.67945 -0.3048)
			(stroke
				(width 0.1)
				(type default)
			)
			(layer "B.Fab")
		)
		(fp_line
			(start 0.12065 -0.305054)
			(end 0.12065 -0.2794)
			(stroke
				(width 0.1)
				(type default)
			)
			(layer "B.Fab")
		)
		(fp_line
			(start 0.67945 -0.305054)
			(end 0.12065 -0.305054)
			(stroke
				(width 0.1)
				(type default)
			)
			(layer "B.Fab")
		)
		(pad "1" smd circle
			(at 0.40005 0 90)
			(size 0 0)
			(layers "B.Cu" "B.Mask" "B.Paste")
			(net "RST_PLD_CPU0_DRAM_AB_N")
		)
		(pad "2" smd circle
			(at -0.40005 0 90)
			(size 0 0)
			(layers "B.Cu" "B.Mask" "B.Paste")
			(net "GND")
		)
	)
	(footprint ""
		(layer "B.Cu")
		(at 57.88152 -315.539882)
		(property "Reference" "R3892"
			(at 0 0 0)
			(layer "B.SilkS")
			(hide yes)
			(effects
				(font
					(size 1.27 1.27)
				)
				(justify mirror)
			)
		)
		(property "Value" ""
			(at 0 0 0)
			(layer "B.Fab")
			(effects
				(font
					(size 1.27 1.27)
				)
				(justify mirror)
			)
		)
		(duplicate_pad_numbers_are_jumpers no)
		(fp_line
			(start -0.7874 -0.4064)
			(end -0.7874 0.4064)
			(stroke
				(width 0.1524)
				(type default)
			)
			(layer "B.SilkS")
		)
		(fp_line
			(start -0.7874 0.4064)
			(end 0.7874 0.4064)
			(stroke
				(width 0.1524)
				(type default)
			)
			(layer "B.SilkS")
		)
		(fp_line
			(start 0.7874 -0.4064)
			(end -0.7874 -0.4064)
			(stroke
				(width 0.1524)
				(type default)
			)
			(layer "B.SilkS")
		)
		(fp_line
			(start 0.7874 0.4064)
			(end 0.7874 -0.4064)
			(stroke
				(width 0.1524)
				(type default)
			)
			(layer "B.SilkS")
		)
		(fp_line
			(start -0.67945 -0.3048)
			(end -0.67945 0.3048)
			(stroke
				(width 0.1)
				(type default)
			)
			(layer "B.Fab")
		)
		(fp_line
			(start -0.67945 0.3048)
			(end -0.120396 0.3048)
			(stroke
				(width 0.1)
				(type default)
			)
			(layer "B.Fab")
		)
		(fp_line
			(start -0.12065 -0.3048)
			(end -0.67945 -0.3048)
			(stroke
				(width 0.1)
				(type default)
			)
			(layer "B.Fab")
		)
		(fp_line
			(start -0.12065 -0.2794)
			(end -0.12065 -0.3048)
			(stroke
				(width 0.1)
				(type default)
			)
			(layer "B.Fab")
		)
		(fp_line
			(start -0.120396 0.2794)
			(end 0.12065 0.2794)
			(stroke
				(width 0.1)
				(type default)
			)
			(layer "B.Fab")
		)
		(fp_line
			(start -0.120396 0.3048)
			(end -0.120396 0.2794)
			(stroke
				(width 0.1)
				(type default)
			)
			(layer "B.Fab")
		)
		(fp_line
			(start 0.12065 -0.305054)
			(end 0.12065 -0.2794)
			(stroke
				(width 0.1)
				(type default)
			)
			(layer "B.Fab")
		)
		(fp_line
			(start 0.12065 -0.2794)
			(end -0.12065 -0.2794)
			(stroke
				(width 0.1)
				(type default)
			)
			(layer "B.Fab")
		)
		(fp_line
			(start 0.12065 0.2794)
			(end 0.12065 0.3048)
			(stroke
				(width 0.1)
				(type default)
			)
			(layer "B.Fab")
		)
		(fp_line
			(start 0.12065 0.3048)
			(end 0.67945 0.3048)
			(stroke
				(width 0.1)
				(type default)
			)
			(layer "B.Fab")
		)
		(fp_line
			(start 0.67945 -0.305054)
			(end 0.12065 -0.305054)
			(stroke
				(width 0.1)
				(type default)
			)
			(layer "B.Fab")
		)
		(fp_line
			(start 0.67945 0.3048)
			(end 0.67945 -0.305054)
			(stroke
				(width 0.1)
				(type default)
			)
			(layer "B.Fab")
		)
		(pad "1" smd circle
			(at 0.40005 0 180)
			(size 0 0)
			(layers "B.Cu" "B.Mask" "B.Paste")
			(net "I3C_SPD_DDRABCD_CPU1_LVC1_SCL_1")
		)
		(pad "2" smd circle
			(at -0.40005 0 180)
			(size 0 0)
			(layers "B.Cu" "B.Mask" "B.Paste")
			(net "I3C_SPD_DDRABCD_CPU1_LVC1_SCL")
		)
	)
)
